# BASEBOARD_FAB2 (Tioga Pass) — schematic netlist excerpt (pin names and nets, part order shuffled) for the footprints in the layout excerpt that follows; sources: Cadence DE-HDL packaged netlist, KiCad conversion of Wiwynn_Tioga_Pass_MB.brd

R3P48  RES  90.9K 1% CHIP  pkg 0402  page 196 : A = P12V_STBY ; B = VSENSE_P12V_ADM1085
R1U57  RES  0.0 5% EMPTY  pkg 0402  page 152 : A = H_CPU1_MEMGHJ_MEMHOT_LVT3_K_N ; B = H_CPU1_MEMGHJ_MEMHOT_G_PCH_N
R6W11  RES  4.75K 1% CHIP  pkg 0402  page 247 : A = SMB_DEBUG_STBY_LVC3_SCL ; B = P3V3_STBY

(kicad_pcb
	(version 20260206)
	(generator "pcbnew")
	(generator_version "10.0")
	(general
		(thickness 1.6)
		(legacy_teardrops no)
	)
	(paper "A4")
	(title_block
		(title "Wiwynn_Tioga_Pass_MB.brd")
		(comment 1 "Tioga Pass / footprints 2864-2866 of 4770")
	)
	(layers
		(0 "F.Cu" signal "TOP")
		(4 "In1.Cu" signal "L2GND")
		(6 "In2.Cu" signal "L3")
		(8 "In3.Cu" signal "L4GND")
		(10 "In4.Cu" signal "L5")
		(12 "In5.Cu" signal "L6GND")
		(14 "In6.Cu" signal "L7VCC")
		(16 "In7.Cu" signal "L8VCC")
		(18 "In8.Cu" signal "L9GND")
		(20 "In9.Cu" signal "L10")
		(22 "In10.Cu" signal "L11GND")
		(24 "In11.Cu" signal "L12")
		(26 "In12.Cu" signal "L13GND")
		(2 "B.Cu" signal "BOTTOM")
		(9 "F.Adhes" user "F.Adhesive")
		(11 "B.Adhes" user "B.Adhesive")
		(13 "F.Paste" user "Package Geometry/Pastemask Top")
		(15 "B.Paste" user "Package Geometry/Pastemask Bottom")
		(5 "F.SilkS" user "Ref Des/Silkscreen Top")
		(7 "B.SilkS" user "Ref Des/Silkscreen Bottom")
		(1 "F.Mask" user "Board Geometry/Soldermask Top")
		(3 "B.Mask" user "Board Geometry/Soldermask Bottom")
		(17 "Dwgs.User" user "User.Drawings")
		(19 "Cmts.User" user "User.Comments")
		(21 "Eco1.User" user "User.Eco1")
		(23 "Eco2.User" user "User.Eco2")
		(25 "Edge.Cuts" user "Board Geometry/Outline")
		(27 "Margin" user)
		(31 "F.CrtYd" user "Package Geometry/Place Bound Top")
		(29 "B.CrtYd" user "Package Geometry/Place Bound Bottom")
		(35 "F.Fab" user "Ref Des/Assembly Top")
		(33 "B.Fab" user "Ref Des/Assembly Bottom")
	)
	(footprint ""
		(layer "B.Cu")
		(at 418.719 -9.017 -90)
		(property "Reference" "R3P48"
			(at 0 0 90)
			(layer "B.SilkS")
			(hide yes)
			(effects
				(font
					(size 1.27 1.27)
				)
				(justify mirror)
			)
		)
		(property "Value" ""
			(at 0 0 90)
			(layer "B.Fab")
			(effects
				(font
					(size 1.27 1.27)
				)
				(justify mirror)
			)
		)
		(duplicate_pad_numbers_are_jumpers no)
		(fp_rect
			(start -0.2794 0.9906)
			(end 0.2794 -0.1016)
			(stroke
				(width 0)
				(type default)
			)
			(fill no)
			(layer "B.CrtYd")
		)
		(fp_line
			(start -0.2794 0.9906)
			(end -0.2794 -0.1016)
			(stroke
				(width 0.1)
				(type default)
			)
			(layer "B.Fab")
		)
		(fp_line
			(start 0.2794 0.9906)
			(end -0.2794 0.9906)
			(stroke
				(width 0.1)
				(type default)
			)
			(layer "B.Fab")
		)
		(fp_line
			(start -0.2794 -0.1016)
			(end 0.2794 -0.1016)
			(stroke
				(width 0.1)
				(type default)
			)
			(layer "B.Fab")
		)
		(fp_line
			(start 0.2794 -0.1016)
			(end 0.2794 0.9906)
			(stroke
				(width 0.1)
				(type default)
			)
			(layer "B.Fab")
		)
		(pad "1" smd rect
			(at 0 0 90)
			(size 0.508 0.508)
			(layers "B.Cu" "B.Mask" "B.Paste")
			(net "P12V_STBY")
		)
		(pad "2" smd rect
			(at 0 0.889 90)
			(size 0.508 0.508)
			(layers "B.Cu" "B.Mask" "B.Paste")
			(net "VSENSE_P12V_ADM1085")
		)
		(zone
			(layer "B.Cu")
			(hatch none 0.5)
			(connect_pads
				(clearance 0)
			)
			(min_thickness 0.25)
			(keepout
				(tracks allowed)
				(vias not_allowed)
				(pads allowed)
				(copperpour not_allowed)
				(footprints allowed)
			)
			(placement
				(enabled no)
				(sheetname "")
			)
			(fill
				(thermal_gap 0.5)
				(thermal_bridge_width 0.5)
				(island_removal_mode 0)
			)
			(polygon
				(pts
					(xy 418.084 -9.271) (xy 418.084 -8.763) (xy 418.465 -8.763) (xy 418.465 -9.271)
				)
			)
		)
		(zone
			(layer "B.Cu")
			(hatch none 0.5)
			(connect_pads
				(clearance 0)
			)
			(min_thickness 0.25)
			(keepout
				(tracks not_allowed)
				(vias allowed)
				(pads allowed)
				(copperpour not_allowed)
				(footprints allowed)
			)
			(placement
				(enabled no)
				(sheetname "")
			)
			(fill
				(thermal_gap 0.5)
				(thermal_bridge_width 0.5)
				(island_removal_mode 0)
			)
			(polygon
				(pts
					(xy 418.084 -9.271) (xy 418.084 -8.763) (xy 418.465 -8.763) (xy 418.465 -9.271)
				)
			)
		)
	)
	(footprint ""
		(layer "B.Cu")
		(at 475.412816 -145.470372 180)
		(property "Reference" "R6W11"
			(at 0.8382 -0.67818 180)
			(unlocked yes)
			(layer "B.SilkS")
			(effects
				(font
					(size 0.4064 0.254)
					(thickness 0.1524)
				)
				(justify left mirror)
			)
		)
		(property "Value" ""
			(at 0 0 0)
			(layer "B.Fab")
			(effects
				(font
					(size 1.27 1.27)
				)
				(justify mirror)
			)
		)
		(duplicate_pad_numbers_are_jumpers no)
		(fp_poly
			(pts
				(xy 0.2794 -0.1016) (xy -0.2794 -0.1016) (xy -0.2794 0.9906) (xy 0.2794 0.9906)
			)
			(stroke
				(width 0)
				(type default)
			)
			(fill no)
			(layer "B.CrtYd")
		)
		(fp_line
			(start 0.2794 0.9906)
			(end -0.2794 0.9906)
			(stroke
				(width 0.1)
				(type default)
			)
			(layer "B.Fab")
		)
		(fp_line
			(start 0.2794 -0.1016)
			(end 0.2794 0.9906)
			(stroke
				(width 0.1)
				(type default)
			)
			(layer "B.Fab")
		)
		(fp_line
			(start -0.2794 0.9906)
			(end -0.2794 -0.1016)
			(stroke
				(width 0.1)
				(type default)
			)
			(layer "B.Fab")
		)
		(fp_line
			(start -0.2794 -0.1016)
			(end 0.2794 -0.1016)
			(stroke
				(width 0.1)
				(type default)
			)
			(layer "B.Fab")
		)
		(pad "1" smd rect
			(at 0 0)
			(size 0.508 0.508)
			(layers "B.Cu" "B.Mask" "B.Paste")
			(net "SMB_DEBUG_STBY_LVC3_SCL")
		)
		(pad "2" smd rect
			(at 0 0.889)
			(size 0.508 0.508)
			(layers "B.Cu" "B.Mask" "B.Paste")
			(net "P3V3_STBY")
		)
		(zone
			(layer "B.Cu")
			(hatch none 0.5)
			(connect_pads
				(clearance 0)
			)
			(min_thickness 0.25)
			(keepout
				(tracks not_allowed)
				(vias allowed)
				(pads allowed)
				(copperpour not_allowed)
				(footprints allowed)
			)
			(placement
				(enabled no)
				(sheetname "")
			)
			(fill
				(thermal_gap 0.5)
				(thermal_bridge_width 0.5)
				(island_removal_mode 0)
			)
			(polygon
				(pts
					(xy 475.158816 -146.105372) (xy 475.666816 -146.105372) (xy 475.666816 -145.724372) (xy 475.158816 -145.724372)
				)
			)
		)
		(zone
			(layer "B.Cu")
			(hatch none 0.5)
			(connect_pads
				(clearance 0)
			)
			(min_thickness 0.25)
			(keepout
				(tracks allowed)
				(vias not_allowed)
				(pads allowed)
				(copperpour not_allowed)
				(footprints allowed)
			)
			(placement
				(enabled no)
				(sheetname "")
			)
			(fill
				(thermal_gap 0.5)
				(thermal_bridge_width 0.5)
				(island_removal_mode 0)
			)
			(polygon
				(pts
					(xy 475.158816 -145.724372) (xy 475.666816 -145.724372) (xy 475.666816 -146.105372) (xy 475.158816 -146.105372)
				)
			)
		)
	)
	(footprint ""
		(layer "B.Cu")
		(at 429.046894 -15.280894 -90)
		(property "Reference" "R1U57"
			(at 0 0 90)
			(layer "B.SilkS")
			(hide yes)
			(effects
				(font
					(size 1.27 1.27)
				)
				(justify mirror)
			)
		)
		(property "Value" ""
			(at 0 0 90)
			(layer "B.Fab")
			(effects
				(font
					(size 1.27 1.27)
				)
				(justify mirror)
			)
		)
		(duplicate_pad_numbers_are_jumpers no)
		(fp_poly
			(pts
				(xy 0.2794 -0.1016) (xy -0.2794 -0.1016) (xy -0.2794 0.9906) (xy 0.2794 0.9906)
			)
			(stroke
				(width 0)
				(type default)
			)
			(fill no)
			(layer "B.CrtYd")
		)
		(fp_line
			(start -0.2794 0.9906)
			(end -0.2794 -0.1016)
			(stroke
				(width 0.1)
				(type default)
			)
			(layer "B.Fab")
		)
		(fp_line
			(start 0.2794 0.9906)
			(end -0.2794 0.9906)
			(stroke
				(width 0.1)
				(type default)
			)
			(layer "B.Fab")
		)
		(fp_line
			(start -0.2794 -0.1016)
			(end 0.2794 -0.1016)
			(stroke
				(width 0.1)
				(type default)
			)
			(layer "B.Fab")
		)
		(fp_line
			(start 0.2794 -0.1016)
			(end 0.2794 0.9906)
			(stroke
				(width 0.1)
				(type default)
			)
			(layer "B.Fab")
		)
		(pad "1" smd rect
			(at 0 0 90)
			(size 0.508 0.508)
			(layers "B.Cu" "B.Mask" "B.Paste")
			(net "H_CPU1_MEMGHJ_MEMHOT_LVT3_K_N")
		)
		(pad "2" smd rect
			(at 0 0.889 90)
			(size 0.508 0.508)
			(layers "B.Cu" "B.Mask" "B.Paste")
			(net "H_CPU1_MEMGHJ_MEMHOT_G_PCH_N")
		)
		(zone
			(layer "B.Cu")
			(hatch none 0.5)
			(connect_pads
				(clearance 0)
			)
			(min_thickness 0.25)
			(keepout
				(tracks not_allowed)
				(vias allowed)
				(pads allowed)
				(copperpour not_allowed)
				(footprints allowed)
			)
			(placement
				(enabled no)
				(sheetname "")
			)
			(fill
				(thermal_gap 0.5)
				(thermal_bridge_width 0.5)
				(island_removal_mode 0)
			)
			(polygon
				(pts
					(xy 428.411894 -15.026894) (xy 428.411894 -15.534894) (xy 428.792894 -15.534894) (xy 428.792894 -15.026894)
				)
			)
		)
		(zone
			(layer "B.Cu")
			(hatch none 0.5)
			(connect_pads
				(clearance 0)
			)
			(min_thickness 0.25)
			(keepout
				(tracks allowed)
				(vias not_allowed)
				(pads allowed)
				(copperpour not_allowed)
				(footprints allowed)
			)
			(placement
				(enabled no)
				(sheetname "")
			)
			(fill
				(thermal_gap 0.5)
				(thermal_bridge_width 0.5)
				(island_removal_mode 0)
			)
			(polygon
				(pts
					(xy 428.792894 -15.026894) (xy 428.792894 -15.534894) (xy 428.411894 -15.534894) (xy 428.411894 -15.026894)
				)
			)
		)
	)
)
